(kicad_pcb
	(version 20260206)
	(generator "pcbnew")
	(generator_version "10.0")
	(general
		(thickness 1.6)
		(legacy_teardrops no)
	)
	(paper "A4")
	(title_block
		(title "netronome-mezz — pcbd0082-001_rev01_jul9_a.brd")
		(comment 1 "Open CloudServer (Microsoft) / footprint 221 of 714 (U2), pads 1-79 of 134")
	)
	(layers
		(0 "F.Cu" signal "TOP")
		(4 "In1.Cu" signal "02_GND")
		(6 "In2.Cu" signal "03_SIG")
		(8 "In3.Cu" signal "04_SIG")
		(10 "In4.Cu" signal "05_GND")
		(12 "In5.Cu" signal "06_PWR1")
		(14 "In6.Cu" signal "07_SIG")
		(16 "In7.Cu" signal "08_SIG")
		(18 "In8.Cu" signal "09_GND")
		(2 "B.Cu" signal "BOTTOM")
		(9 "F.Adhes" user "F.Adhesive")
		(11 "B.Adhes" user "B.Adhesive")
		(13 "F.Paste" user "Package Geometry/Pastemask Top")
		(15 "B.Paste" user "Package Geometry/Pastemask Bottom")
		(5 "F.SilkS" user "Ref Des/Silkscreen Top")
		(7 "B.SilkS" user "Ref Des/Silkscreen Bottom")
		(1 "F.Mask" user "Board Geometry/Soldermask Top")
		(3 "B.Mask" user "Board Geometry/Soldermask Bottom")
		(17 "Dwgs.User" user "User.Drawings")
		(19 "Cmts.User" user "User.Comments")
		(21 "Eco1.User" user "User.Eco1")
		(23 "Eco2.User" user "User.Eco2")
		(25 "Edge.Cuts" user "Board Geometry/Outline")
		(27 "Margin" user)
		(31 "F.CrtYd" user "Package Geometry/Place Bound Top")
		(29 "B.CrtYd" user "Package Geometry/Place Bound Bottom")
		(35 "F.Fab" user "Ref Des/Assembly Top")
		(33 "B.Fab" user "Ref Des/Assembly Bottom")
		(45 "User.4" user "COMPVAL_TYPE_BOTTOM")
	)
	(footprint ""
		(layer "F.Cu")
		(at 31.496 25.2984 180)
		(property "Reference" "U2"
			(at 3.81 5.84073 0)
			(unlocked yes)
			(layer "F.SilkS")
			(effects
				(font
					(size 0.7874 0.5842)
					(thickness 0.127)
				)
				(justify left)
			)
		)
		(property "Value" "*"
			(at -0.4826 -0.148209 180)
			(unlocked yes)
			(layer "F.Fab")
			(hide yes)
			(effects
				(font
					(size 1.27 0.9652)
					(thickness 0.000001)
				)
				(justify left)
			)
		)
		(property "Device Type" "PROG0057"
			(at -0.4826 -0.148209 180)
			(unlocked yes)
			(layer "F.Fab")
			(hide yes)
			(effects
				(font
					(size 1.27 0.9652)
					(thickness 0.000001)
				)
				(justify left)
			)
		)
		(duplicate_pad_numbers_are_jumpers no)
		(pad "" smd circle
			(at -5.207 -4.826 180)
			(size 1.0668 1.0668)
			(layers "F.Cu" "F.Mask" "F.Paste")
		)
		(pad "" smd circle
			(at 4.826 5.588 180)
			(size 1.0668 1.0668)
			(layers "F.Cu" "F.Mask" "F.Paste")
		)
		(pad "A1" smd circle
			(at -3.250006 -3.250006 180)
			(size 0.254 0.254)
			(layers "F.Cu" "F.Mask" "F.Paste")
			(net "EXT_3.3V")
		)
		(pad "A2" smd circle
			(at -2.750007 -3.250006 180)
			(size 0.254 0.254)
			(layers "F.Cu" "F.Mask" "F.Paste")
			(net "_NC_NWK0_LED_LINK_Y_L")
		)
		(pad "A3" smd circle
			(at -2.250008 -3.250006 180)
			(size 0.254 0.254)
			(layers "F.Cu" "F.Mask" "F.Paste")
			(net "_NC_NWK0_LED_ACT_Y_L")
		)
		(pad "A4" smd circle
			(at -1.750009 -3.250006 180)
			(size 0.254 0.254)
			(layers "F.Cu" "F.Mask" "F.Paste")
			(net "9N1879")
		)
		(pad "A5" smd circle
			(at -1.25001 -3.250006 180)
			(size 0.254 0.254)
			(layers "F.Cu" "F.Mask" "F.Paste")
			(net "GND")
		)
		(pad "A6" smd circle
			(at -0.750011 -3.250006 180)
			(size 0.254 0.254)
			(layers "F.Cu" "F.Mask" "F.Paste")
			(net "CPLD_PGRM_JTAG_TMS")
		)
		(pad "A7" smd circle
			(at -0.250012 -3.250006 180)
			(size 0.254 0.254)
			(layers "F.Cu" "F.Mask" "F.Paste")
			(net "_NC_NWK0_MOD_INT_L")
		)
		(pad "A8" smd circle
			(at 0.250012 -3.250006 180)
			(size 0.254 0.254)
			(layers "F.Cu" "F.Mask" "F.Paste")
			(net "_NC_CPLD_28")
		)
		(pad "A9" smd circle
			(at 0.750011 -3.250006 180)
			(size 0.254 0.254)
			(layers "F.Cu" "F.Mask" "F.Paste")
			(net "_NC_NWK0_MOD_RESET_L")
		)
		(pad "A10" smd circle
			(at 1.25001 -3.250006 180)
			(size 0.254 0.254)
			(layers "F.Cu" "F.Mask" "F.Paste")
			(net "_NC_CPLD_27")
		)
		(pad "A11" smd circle
			(at 1.750009 -3.250006 180)
			(size 0.254 0.254)
			(layers "F.Cu" "F.Mask" "F.Paste")
			(net "_NC_NWK1_LED_LINK_Y_L")
		)
		(pad "A12" smd circle
			(at 2.250008 -3.250006 180)
			(size 0.254 0.254)
			(layers "F.Cu" "F.Mask" "F.Paste")
			(net "_NC_CPLD_24")
		)
		(pad "A13" smd circle
			(at 2.750007 -3.250006 180)
			(size 0.254 0.254)
			(layers "F.Cu" "F.Mask" "F.Paste")
			(net "NWK1_LED_ACT_G_L")
		)
		(pad "A14" smd circle
			(at 3.250006 -3.250006 180)
			(size 0.254 0.254)
			(layers "F.Cu" "F.Mask" "F.Paste")
			(net "_NC_CPLD_21")
		)
		(pad "B1" smd circle
			(at -3.250006 -2.750007 180)
			(size 0.254 0.254)
			(layers "F.Cu" "F.Mask" "F.Paste")
			(net "_NC_CPLD_0")
		)
		(pad "B2" smd circle
			(at -2.750007 -2.750007 180)
			(size 0.254 0.254)
			(layers "F.Cu" "F.Mask" "F.Paste")
			(net "_NC_CPLD_1")
		)
		(pad "B3" thru_hole circle
			(at -2.250008 -2.750007 180)
			(size 0.3048 0.3048)
			(drill 0.127)
			(layers "*.Cu" "*.Mask")
			(remove_unused_layers no)
			(net "NWK0_LED_LINK_G_L")
			(clearance 0.1143)
			(thermal_gap 0.1143)
			(padstack
				(mode front_inner_back)
				(layer "Inner"
					(shape circle)
					(size 0 0)
				)
				(layer "B.Cu"
					(shape circle)
					(size 0.3556 0.3556)
					(clearance 0.0889)
				)
			)
		)
		(pad "B4" thru_hole circle
			(at -1.750009 -2.750007 180)
			(size 0.3048 0.3048)
			(drill 0.127)
			(layers "*.Cu" "*.Mask")
			(remove_unused_layers no)
			(net "CPLD_PGRM_JTAG_TDI")
			(clearance 0.1143)
			(thermal_gap 0.1143)
			(padstack
				(mode front_inner_back)
				(layer "Inner"
					(shape circle)
					(size 0 0)
				)
				(layer "B.Cu"
					(shape circle)
					(size 0.3556 0.3556)
					(clearance 0.0889)
				)
			)
		)
		(pad "B5" smd circle
			(at -1.25001 -2.750007 180)
			(size 0.254 0.254)
			(layers "F.Cu" "F.Mask" "F.Paste")
			(net "_NC_CPLD_30")
		)
		(pad "B6" thru_hole circle
			(at -0.750011 -2.750007 180)
			(size 0.3048 0.3048)
			(drill 0.127)
			(layers "*.Cu" "*.Mask")
			(remove_unused_layers no)
			(net "CPLD_PGRM_JTAG_TCK")
			(clearance 0.1143)
			(thermal_gap 0.1143)
			(padstack
				(mode front_inner_back)
				(layer "Inner"
					(shape circle)
					(size 0 0)
				)
				(layer "B.Cu"
					(shape circle)
					(size 0.3556 0.3556)
					(clearance 0.0889)
				)
			)
		)
		(pad "B7" thru_hole circle
			(at -0.250012 -2.750007 180)
			(size 0.3048 0.3048)
			(drill 0.127)
			(layers "*.Cu" "*.Mask")
			(remove_unused_layers no)
			(net "NWK0_MOD_PRES_L")
			(clearance 0.1143)
			(thermal_gap 0.1143)
			(padstack
				(mode front_inner_back)
				(layer "Inner"
					(shape circle)
					(size 0 0)
				)
				(layer "B.Cu"
					(shape circle)
					(size 0.3556 0.3556)
					(clearance 0.0889)
				)
			)
		)
		(pad "B8" thru_hole circle
			(at 0.250012 -2.750007 180)
			(size 0.3048 0.3048)
			(drill 0.127)
			(layers "*.Cu" "*.Mask")
			(remove_unused_layers no)
			(net "PSU_I2C_SDA")
			(clearance 0.1143)
			(thermal_gap 0.1143)
			(padstack
				(mode front_inner_back)
				(layer "Inner"
					(shape circle)
					(size 0 0)
				)
				(layer "B.Cu"
					(shape circle)
					(size 0.3556 0.3556)
					(clearance 0.0889)
				)
			)
		)
		(pad "B9" smd circle
			(at 0.750011 -2.750007 180)
			(size 0.254 0.254)
			(layers "F.Cu" "F.Mask" "F.Paste")
			(net "_NC_NWK0_MOD_SEL_L")
		)
		(pad "B10" thru_hole circle
			(at 1.25001 -2.750007 180)
			(size 0.3048 0.3048)
			(drill 0.127)
			(layers "*.Cu" "*.Mask")
			(remove_unused_layers no)
			(net "EXT_3.3V")
			(clearance 0.1143)
			(thermal_gap 0.1143)
			(padstack
				(mode front_inner_back)
				(layer "Inner"
					(shape circle)
					(size 0 0)
				)
				(layer "B.Cu"
					(shape circle)
					(size 0.3556 0.3556)
					(clearance 0.0889)
				)
			)
		)
		(pad "B11" thru_hole circle
			(at 1.750009 -2.750007 180)
			(size 0.3048 0.3048)
			(drill 0.127)
			(layers "*.Cu" "*.Mask")
			(remove_unused_layers no)
			(net "GND")
			(clearance 0.1143)
			(thermal_gap 0.1143)
			(padstack
				(mode front_inner_back)
				(layer "Inner"
					(shape circle)
					(size 0 0)
				)
				(layer "B.Cu"
					(shape circle)
					(size 0.3556 0.3556)
					(clearance 0.0889)
				)
			)
		)
		(pad "B12" smd circle
			(at 2.250008 -2.750007 180)
			(size 0.254 0.254)
			(layers "F.Cu" "F.Mask" "F.Paste")
			(net "_NC_CPLD_GPIO8")
		)
		(pad "B13" smd circle
			(at 2.750007 -2.750007 180)
			(size 0.254 0.254)
			(layers "F.Cu" "F.Mask" "F.Paste")
			(net "_NC_NWK1_LED_ACT_Y_L")
		)
		(pad "B14" smd circle
			(at 3.250006 -2.750007 180)
			(size 0.254 0.254)
			(layers "F.Cu" "F.Mask" "F.Paste")
			(net "_NC_NWK1_MOD_INT_L")
		)
		(pad "C1" smd circle
			(at -3.250006 -2.250008 180)
			(size 0.254 0.254)
			(layers "F.Cu" "F.Mask" "F.Paste")
			(net "EXT_12.0V_PGOOD")
		)
		(pad "C2" thru_hole circle
			(at -2.750007 -2.250008 180)
			(size 0.3048 0.3048)
			(drill 0.127)
			(layers "*.Cu" "*.Mask")
			(remove_unused_layers no)
			(net "VDD_5.0V_PGOOD")
			(clearance 0.1143)
			(thermal_gap 0.1143)
			(padstack
				(mode front_inner_back)
				(layer "Inner"
					(shape circle)
					(size 0 0)
				)
				(layer "B.Cu"
					(shape circle)
					(size 0.3556 0.3556)
					(clearance 0.0889)
				)
			)
		)
		(pad "C3" smd circle
			(at -2.250008 -2.250008 180)
			(size 0.254 0.254)
			(layers "F.Cu" "F.Mask" "F.Paste")
			(net "EXT_3.3V_PGOOD")
		)
		(pad "C4" smd circle
			(at -1.750009 -2.250008 180)
			(size 0.254 0.254)
			(layers "F.Cu" "F.Mask" "F.Paste")
			(net "NWK0_LED_ACT_G_L")
		)
		(pad "C5" smd circle
			(at -1.25001 -2.250008 180)
			(size 0.254 0.254)
			(layers "F.Cu" "F.Mask" "F.Paste")
			(net "EXT_3.3V")
		)
		(pad "C6" smd circle
			(at -0.750011 -2.250008 180)
			(size 0.254 0.254)
			(layers "F.Cu" "F.Mask" "F.Paste")
			(net "_NC_CPLD_29")
		)
		(pad "C7" smd circle
			(at -0.250012 -2.250008 180)
			(size 0.254 0.254)
			(layers "F.Cu" "F.Mask" "F.Paste")
			(net "_NC_CPLD_31")
		)
		(pad "C8" smd circle
			(at 0.250012 -2.250008 180)
			(size 0.254 0.254)
			(layers "F.Cu" "F.Mask" "F.Paste")
			(net "PSU_I2C_SCL")
		)
		(pad "C9" smd circle
			(at 0.750011 -2.250008 180)
			(size 0.254 0.254)
			(layers "F.Cu" "F.Mask" "F.Paste")
			(net "_NC_NWK0_MOD_LP_MODE")
		)
		(pad "C10" smd circle
			(at 1.25001 -2.250008 180)
			(size 0.254 0.254)
			(layers "F.Cu" "F.Mask" "F.Paste")
			(net "_NC_NWK0_MOD_RS_1")
		)
		(pad "C11" smd circle
			(at 1.750009 -2.250008 180)
			(size 0.254 0.254)
			(layers "F.Cu" "F.Mask" "F.Paste")
			(net "_NC_CPLD_26")
		)
		(pad "C12" smd circle
			(at 2.250008 -2.250008 180)
			(size 0.254 0.254)
			(layers "F.Cu" "F.Mask" "F.Paste")
			(net "_NC_CPLD_25")
		)
		(pad "C13" thru_hole circle
			(at 2.750007 -2.250008 180)
			(size 0.3048 0.3048)
			(drill 0.127)
			(layers "*.Cu" "*.Mask")
			(remove_unused_layers no)
			(net "NWK1_MOD_PRES_L")
			(clearance 0.1143)
			(thermal_gap 0.1143)
			(padstack
				(mode front_inner_back)
				(layer "Inner"
					(shape circle)
					(size 0 0)
				)
				(layer "B.Cu"
					(shape circle)
					(size 0.3556 0.3556)
					(clearance 0.0889)
				)
			)
		)
		(pad "C14" smd circle
			(at 3.250006 -2.250008 180)
			(size 0.254 0.254)
			(layers "F.Cu" "F.Mask" "F.Paste")
			(net "_NC_CPLD_23")
		)
		(pad "D1" smd circle
			(at -3.250006 -1.750009 180)
			(size 0.254 0.254)
			(layers "F.Cu" "F.Mask" "F.Paste")
			(net "VDD_7401_PGOOD")
		)
		(pad "D2" thru_hole circle
			(at -2.750007 -1.750009 180)
			(size 0.3048 0.3048)
			(drill 0.127)
			(layers "*.Cu" "*.Mask")
			(remove_unused_layers no)
			(net "GND")
			(clearance 0.1143)
			(thermal_gap 0.1143)
			(padstack
				(mode front_inner_back)
				(layer "Inner"
					(shape circle)
					(size 0 0)
				)
				(layer "B.Cu"
					(shape circle)
					(size 0.3556 0.3556)
					(clearance 0.0889)
				)
			)
		)
		(pad "D3" smd circle
			(at -2.250008 -1.750009 180)
			(size 0.254 0.254)
			(layers "F.Cu" "F.Mask" "F.Paste")
			(net "EXT_3.3V")
		)
		(pad "D12" smd circle
			(at 2.250008 -1.750009 180)
			(size 0.254 0.254)
			(layers "F.Cu" "F.Mask" "F.Paste")
			(net "_NC_CPLD_22")
		)
		(pad "D13" thru_hole circle
			(at 2.750007 -1.750009 180)
			(size 0.3048 0.3048)
			(drill 0.127)
			(layers "*.Cu" "*.Mask")
			(remove_unused_layers no)
			(net "GND")
			(clearance 0.1143)
			(thermal_gap 0.1143)
			(padstack
				(mode front_inner_back)
				(layer "Inner"
					(shape circle)
					(size 0 0)
				)
				(layer "B.Cu"
					(shape circle)
					(size 0.3556 0.3556)
					(clearance 0.0889)
				)
			)
		)
		(pad "D14" smd circle
			(at 3.250006 -1.750009 180)
			(size 0.254 0.254)
			(layers "F.Cu" "F.Mask" "F.Paste")
			(net "EXT_3.3V")
		)
		(pad "E1" smd circle
			(at -3.250006 -1.25001 180)
			(size 0.254 0.254)
			(layers "F.Cu" "F.Mask" "F.Paste")
			(net "VDDQ_VTT_PGOOD")
		)
		(pad "E2" thru_hole circle
			(at -2.750007 -1.25001 180)
			(size 0.3048 0.3048)
			(drill 0.127)
			(layers "*.Cu" "*.Mask")
			(remove_unused_layers no)
			(net "VDD_CORE_PGOOD")
			(clearance 0.1143)
			(thermal_gap 0.1143)
			(padstack
				(mode front_inner_back)
				(layer "Inner"
					(shape circle)
					(size 0 0)
				)
				(layer "B.Cu"
					(shape circle)
					(size 0.3556 0.3556)
					(clearance 0.0889)
				)
			)
		)
		(pad "E3" smd circle
			(at -2.250008 -1.25001 180)
			(size 0.254 0.254)
			(layers "F.Cu" "F.Mask" "F.Paste")
			(net "CORE_FB_FAULT_L")
		)
		(pad "E12" smd circle
			(at 2.250008 -1.25001 180)
			(size 0.254 0.254)
			(layers "F.Cu" "F.Mask" "F.Paste")
			(net "_NC_NWK1_MOD_LP_MODE")
		)
		(pad "E13" smd circle
			(at 2.750007 -1.25001 180)
			(size 0.254 0.254)
			(layers "F.Cu" "F.Mask" "F.Paste")
			(net "_NC_NWK1_MOD_SEL_L")
		)
		(pad "E14" smd circle
			(at 3.250006 -1.25001 180)
			(size 0.254 0.254)
			(layers "F.Cu" "F.Mask" "F.Paste")
			(net "_NC_NWK1_MOD_RESET_L")
		)
		(pad "F1" smd circle
			(at -3.250006 -0.750011 180)
			(size 0.254 0.254)
			(layers "F.Cu" "F.Mask" "F.Paste")
			(net "_NC_CPLD_2")
		)
		(pad "F2" thru_hole circle
			(at -2.750007 -0.750011 180)
			(size 0.3048 0.3048)
			(drill 0.127)
			(layers "*.Cu" "*.Mask")
			(remove_unused_layers no)
			(net "CORE_FB_ALERT_L")
			(clearance 0.1143)
			(thermal_gap 0.1143)
			(padstack
				(mode front_inner_back)
				(layer "Inner"
					(shape circle)
					(size 0 0)
				)
				(layer "B.Cu"
					(shape circle)
					(size 0.3556 0.3556)
					(clearance 0.0889)
				)
			)
		)
		(pad "F3" smd circle
			(at -2.250008 -0.750011 180)
			(size 0.254 0.254)
			(layers "F.Cu" "F.Mask" "F.Paste")
			(net "_NC_CPLD_3")
		)
		(pad "F12" smd circle
			(at 2.250008 -0.750011 180)
			(size 0.254 0.254)
			(layers "F.Cu" "F.Mask" "F.Paste")
			(net "_NC_NWK1_MOD_RS_1")
		)
		(pad "F13" thru_hole circle
			(at 2.750007 -0.750011 180)
			(size 0.3048 0.3048)
			(drill 0.127)
			(layers "*.Cu" "*.Mask")
			(remove_unused_layers no)
			(net "CPLD_NFP_RST_LED_L")
			(clearance 0.1143)
			(thermal_gap 0.1143)
			(padstack
				(mode front_inner_back)
				(layer "Inner"
					(shape circle)
					(size 0 0)
				)
				(layer "B.Cu"
					(shape circle)
					(size 0.3556 0.3556)
					(clearance 0.0889)
				)
			)
		)
		(pad "F14" smd circle
			(at 3.250006 -0.750011 180)
			(size 0.254 0.254)
			(layers "F.Cu" "F.Mask" "F.Paste")
			(net "PWR_GOOD_LED_L")
		)
		(pad "G1" smd circle
			(at -3.250006 -0.250012 180)
			(size 0.254 0.254)
			(layers "F.Cu" "F.Mask" "F.Paste")
			(net "_NC_CPLD_4")
		)
		(pad "G2" thru_hole circle
			(at -2.750007 -0.250012 180)
			(size 0.3048 0.3048)
			(drill 0.127)
			(layers "*.Cu" "*.Mask")
			(remove_unused_layers no)
			(net "GND")
			(clearance 0.1143)
			(thermal_gap 0.1143)
			(padstack
				(mode front_inner_back)
				(layer "Inner"
					(shape circle)
					(size 0 0)
				)
				(layer "B.Cu"
					(shape circle)
					(size 0.3556 0.3556)
					(clearance 0.0889)
				)
			)
		)
		(pad "G3" smd circle
			(at -2.250008 -0.250012 180)
			(size 0.254 0.254)
			(layers "F.Cu" "F.Mask" "F.Paste")
			(net "CORE_FB_PH1_THERM_L")
		)
		(pad "G12" smd circle
			(at 2.250008 -0.250012 180)
			(size 0.254 0.254)
			(layers "F.Cu" "F.Mask" "F.Paste")
			(net "CPLD_CORE_PSI_L")
		)
		(pad "G13" thru_hole circle
			(at 2.750007 -0.250012 180)
			(size 0.3048 0.3048)
			(drill 0.127)
			(layers "*.Cu" "*.Mask")
			(remove_unused_layers no)
			(net "VDD_CORE_EN")
			(clearance 0.1143)
			(thermal_gap 0.1143)
			(padstack
				(mode front_inner_back)
				(layer "Inner"
					(shape circle)
					(size 0 0)
				)
				(layer "B.Cu"
					(shape circle)
					(size 0.3556 0.3556)
					(clearance 0.0889)
				)
			)
		)
		(pad "G14" smd circle
			(at 3.250006 -0.250012 180)
			(size 0.254 0.254)
			(layers "F.Cu" "F.Mask" "F.Paste")
			(net "VDD_7401_EN")
		)
		(pad "H1" smd circle
			(at -3.250006 0.250012 180)
			(size 0.254 0.254)
			(layers "F.Cu" "F.Mask" "F.Paste")
			(net "HOST_RESET_REQ_L")
		)
		(pad "H2" thru_hole circle
			(at -2.750007 0.250012 180)
			(size 0.3048 0.3048)
			(drill 0.127)
			(layers "*.Cu" "*.Mask")
			(remove_unused_layers no)
			(net "CORE_FB_PH2_THERM_L")
			(clearance 0.1143)
			(thermal_gap 0.1143)
			(padstack
				(mode front_inner_back)
				(layer "Inner"
					(shape circle)
					(size 0 0)
				)
				(layer "B.Cu"
					(shape circle)
					(size 0.3556 0.3556)
					(clearance 0.0889)
				)
			)
		)
		(pad "H3" smd circle
			(at -2.250008 0.250012 180)
			(size 0.254 0.254)
			(layers "F.Cu" "F.Mask" "F.Paste")
			(net "CPLD_NIC_MEZZ_ID1")
		)
		(pad "H12" smd circle
			(at 2.250008 0.250012 180)
			(size 0.254 0.254)
			(layers "F.Cu" "F.Mask" "F.Paste")
			(net "VDDQ_VTT_EN")
		)
		(pad "H13" thru_hole circle
			(at 2.750007 0.250012 180)
			(size 0.3048 0.3048)
			(drill 0.127)
			(layers "*.Cu" "*.Mask")
			(remove_unused_layers no)
			(net "GND")
			(clearance 0.1143)
			(thermal_gap 0.1143)
			(padstack
				(mode front_inner_back)
				(layer "Inner"
					(shape circle)
					(size 0 0)
				)
				(layer "B.Cu"
					(shape circle)
					(size 0.3556 0.3556)
					(clearance 0.0889)
				)
			)
		)
		(pad "H14" smd circle
			(at 3.250006 0.250012 180)
			(size 0.254 0.254)
			(layers "F.Cu" "F.Mask" "F.Paste")
			(net "_NC_CPLD_20")
		)
		(pad "J1" smd circle
			(at -3.250006 0.750011 180)
			(size 0.254 0.254)
			(layers "F.Cu" "F.Mask" "F.Paste")
			(net "NFP_CLK_NRESET_OUT_L")
		)
		(pad "J2" thru_hole circle
			(at -2.750007 0.750011 180)
			(size 0.3048 0.3048)
			(drill 0.127)
			(layers "*.Cu" "*.Mask")
			(remove_unused_layers no)
			(net "CNTRL_SPI_SCK")
			(clearance 0.1143)
			(thermal_gap 0.1143)
			(padstack
				(mode front_inner_back)
				(layer "Inner"
					(shape circle)
					(size 0 0)
				)
				(layer "B.Cu"
					(shape circle)
					(size 0.3556 0.3556)
					(clearance 0.0889)
				)
			)
		)
		(pad "J3" smd circle
			(at -2.250008 0.750011 180)
			(size 0.254 0.254)
			(layers "F.Cu" "F.Mask" "F.Paste")
			(net "CNTRL_SPI_MISO")
		)
		(pad "J12" smd circle
			(at 2.250008 0.750011 180)
			(size 0.254 0.254)
			(layers "F.Cu" "F.Mask" "F.Paste")
			(net "_NC_CPLD_19")
		)
		(pad "J13" thru_hole circle
			(at 2.750007 0.750011 180)
			(size 0.3048 0.3048)
			(drill 0.127)
			(layers "*.Cu" "*.Mask")
			(remove_unused_layers no)
			(net "VDD_5.0V_EN")
			(clearance 0.1143)
			(thermal_gap 0.1143)
			(padstack
				(mode front_inner_back)
				(layer "Inner"
					(shape circle)
					(size 0 0)
				)
				(layer "B.Cu"
					(shape circle)
					(size 0.3556 0.3556)
					(clearance 0.0889)
				)
			)
		)
	)
)
